(kicad_pcb
	(version 20241229)
	(generator "pcbnew")
	(generator_version "9.0")
	(general
		(thickness 1.552)
		(legacy_teardrops no)
	)
	(paper "A4")
	(title_block
		(date "2023-07-25")
		(rev "1.1.4")
		(comment 9 "footprints 364-367 of 379")
	)
	(layers
		(0 "F.Cu" signal)
		(4 "In1.Cu" signal)
		(6 "In2.Cu" signal)
		(8 "In3.Cu" signal)
		(10 "In4.Cu" signal)
		(12 "In5.Cu" signal)
		(14 "In6.Cu" signal)
		(2 "B.Cu" signal)
		(9 "F.Adhes" user "F.Adhesive")
		(11 "B.Adhes" user "B.Adhesive")
		(13 "F.Paste" user)
		(15 "B.Paste" user)
		(5 "F.SilkS" user "F.Silkscreen")
		(7 "B.SilkS" user "B.Silkscreen")
		(1 "F.Mask" user)
		(3 "B.Mask" user)
		(17 "Dwgs.User" user "User.Drawings")
		(19 "Cmts.User" user "User.Comments")
		(21 "Eco1.User" user "User.Eco1")
		(23 "Eco2.User" user "User.Eco2")
		(25 "Edge.Cuts" user)
		(27 "Margin" user)
		(31 "F.CrtYd" user "F.Courtyard")
		(29 "B.CrtYd" user "B.Courtyard")
		(35 "F.Fab" user)
		(33 "B.Fab" user)
	)
	(footprint "antmicro-footprints:R_0402_1005Metric"
		(layer "B.Cu")
		(at 120.37 63.42)
		(descr "Resistor SMD 0402")
		(tags "resistor SMD 0402")
		(property "Reference" "R47"
			(at 0.66 1.32 180)
			(layer "B.SilkS")
			(effects
				(font
					(size 0.65 0.65)
					(thickness 0.15)
				)
				(justify left bottom mirror)
			)
		)
		(property "Value" "R_240R_0402"
			(at 0 -1.4 180)
			(layer "B.Fab")
			(hide yes)
			(effects
				(font
					(size 0.7 0.7)
					(thickness 0.15)
				)
				(justify left bottom mirror)
			)
		)
		(property "Datasheet" "https://www.bourns.com/docs/product-datasheets/cr.pdf"
			(at 0 0 0)
			(layer "F.Fab")
			(hide yes)
			(effects
				(font
					(size 1.27 1.27)
					(thickness 0.15)
				)
			)
		)
		(property "Description" "SMD Chip Resistor, 240 ohm, ± 1%, 63 mW, 0402 [1005 Metric], Thick Film, General Purpose"
			(at 0 0 0)
			(layer "F.Fab")
			(hide yes)
			(effects
				(font
					(size 1.27 1.27)
					(thickness 0.15)
				)
			)
		)
		(property "Author" "Antmicro"
			(at 0 0 0)
			(layer "B.Fab")
			(hide yes)
			(effects
				(font
					(size 1 1)
					(thickness 0.15)
				)
				(justify mirror)
			)
		)
		(property "License" "Apache-2.0"
			(at 0 0 0)
			(layer "B.Fab")
			(hide yes)
			(effects
				(font
					(size 1 1)
					(thickness 0.15)
				)
				(justify mirror)
			)
		)
		(property "MPN" "CR0402-FX-2400GLF"
			(at 0 0 0)
			(layer "B.Fab")
			(hide yes)
			(effects
				(font
					(size 1 1)
					(thickness 0.15)
				)
				(justify mirror)
			)
		)
		(property "Manufacturer" "Bourns"
			(at 0 0 0)
			(layer "B.Fab")
			(hide yes)
			(effects
				(font
					(size 1 1)
					(thickness 0.15)
				)
				(justify mirror)
			)
		)
		(property "Tolerance" "1%"
			(at 0 0 0)
			(layer "B.Fab")
			(hide yes)
			(effects
				(font
					(size 1 1)
					(thickness 0.15)
				)
				(justify mirror)
			)
		)
		(property "Val" "240R"
			(at 0 0 0)
			(layer "B.Fab")
			(hide yes)
			(effects
				(font
					(size 1 1)
					(thickness 0.15)
				)
				(justify mirror)
			)
		)
		(sheetname "/DDR3/")
		(sheetfile "ddr3.kicad_sch")
		(attr smd)
		(fp_rect
			(start -0.925 0.47)
			(end 0.925 -0.47)
			(stroke
				(width 0.05)
				(type default)
			)
			(fill no)
			(layer "B.CrtYd")
		)
		(fp_rect
			(start -0.5 0.25)
			(end 0.5 -0.25)
			(stroke
				(width 0.15)
				(type solid)
			)
			(fill no)
			(layer "B.Fab")
		)
		(fp_text user "${REFERENCE}"
			(at -0.95 -3.168 180)
			(layer "B.Fab")
			(effects
				(font
					(size 0.7 0.7)
					(thickness 0.15)
				)
				(justify left bottom mirror)
			)
		)
		(fp_text user "License: Apache-2.0"
			(at -0.95 -5.169 180)
			(layer "B.Fab")
			(effects
				(font
					(size 0.7 0.7)
					(thickness 0.15)
				)
				(justify left bottom mirror)
			)
		)
		(fp_text user "Author: Antmicro"
			(at -0.95 -4.169 180)
			(layer "B.Fab")
			(effects
				(font
					(size 0.7 0.7)
					(thickness 0.15)
				)
				(justify left bottom mirror)
			)
		)
		(pad "1" smd roundrect
			(at -0.48 0)
			(size 0.59 0.64)
			(layers "B.Cu" "B.Mask" "B.Paste")
			(roundrect_rratio 0.25)
			(net 1 "GND")
			(pintype "passive")
		)
		(pad "2" smd roundrect
			(at 0.48 0)
			(size 0.59 0.64)
			(layers "B.Cu" "B.Mask" "B.Paste")
			(roundrect_rratio 0.25)
			(net 287 "Net-(U12A-ZQ)")
			(pintype "passive")
		)
	)
	(footprint "antmicro-footprints:C_0201"
		(layer "B.Cu")
		(at 127.45 90.24)
		(descr "Capacitor SMD 0201")
		(tags "capacitor SMD 0201")
		(property "Reference" "C99"
			(at -10.22 -12.235736 0)
			(layer "B.SilkS")
			(effects
				(font
					(size 0.65 0.65)
					(thickness 0.15)
				)
				(justify right bottom mirror)
			)
		)
		(property "Value" "C_100n_0201"
			(at 0 -1.4 0)
			(layer "B.Fab")
			(hide yes)
			(effects
				(font
					(size 0.7 0.7)
					(thickness 0.15)
				)
				(justify right bottom mirror)
			)
		)
		(property "Datasheet" "https://www.yageo.com/en/Chart/Download/pdf/CC0201KRX6S5BB104"
			(at 0 0 0)
			(layer "F.Fab")
			(hide yes)
			(effects
				(font
					(size 1.27 1.27)
					(thickness 0.15)
				)
			)
		)
		(property "Description" "SMD Multilayer Ceramic Capacitor, 0.1 µF, 6.3 V, 0201 [0603 Metric], ± 10%, X6S, CC Series"
			(at 0 0 0)
			(layer "F.Fab")
			(hide yes)
			(effects
				(font
					(size 1.27 1.27)
					(thickness 0.15)
				)
			)
		)
		(property "Author" "Antmicro"
			(at 0 0 0)
			(layer "B.Fab")
			(hide yes)
			(effects
				(font
					(size 1 1)
					(thickness 0.15)
				)
				(justify mirror)
			)
		)
		(property "Dielectric" ""
			(at 0 0 0)
			(layer "B.Fab")
			(hide yes)
			(effects
				(font
					(size 1 1)
					(thickness 0.15)
				)
				(justify mirror)
			)
		)
		(property "License" "Apache-2.0"
			(at 0 0 0)
			(layer "B.Fab")
			(hide yes)
			(effects
				(font
					(size 1 1)
					(thickness 0.15)
				)
				(justify mirror)
			)
		)
		(property "MPN" "CC0201KRX6S5BB104"
			(at 0 0 0)
			(layer "B.Fab")
			(hide yes)
			(effects
				(font
					(size 1 1)
					(thickness 0.15)
				)
				(justify mirror)
			)
		)
		(property "Manufacturer" "YAGEO"
			(at 0 0 0)
			(layer "B.Fab")
			(hide yes)
			(effects
				(font
					(size 1 1)
					(thickness 0.15)
				)
				(justify mirror)
			)
		)
		(property "Val" "100n"
			(at 0 0 0)
			(layer "B.Fab")
			(hide yes)
			(effects
				(font
					(size 1 1)
					(thickness 0.15)
				)
				(justify mirror)
			)
		)
		(property "Voltage" ""
			(at 0 0 0)
			(layer "B.Fab")
			(hide yes)
			(effects
				(font
					(size 1 1)
					(thickness 0.15)
				)
				(justify mirror)
			)
		)
		(property "Public" "False"
			(at 0 0 0)
			(unlocked yes)
			(layer "B.Fab")
			(hide yes)
			(effects
				(font
					(size 1 1)
					(thickness 0.15)
				)
				(justify mirror)
			)
		)
		(sheetname "/FPGA Power/")
		(sheetfile "FPGA_Power.kicad_sch")
		(attr smd)
		(fp_rect
			(start -0.7 0.35)
			(end 0.7 -0.35)
			(stroke
				(width 0.05)
				(type default)
			)
			(fill no)
			(layer "B.CrtYd")
		)
		(fp_rect
			(start 0.3 -0.15)
			(end -0.301 0.149)
			(stroke
				(width 0.15)
				(type solid)
			)
			(fill no)
			(layer "B.Fab")
		)
		(fp_text user "License: Apache-2.0"
			(at -0.72 -4.4 180)
			(layer "B.Fab")
			(effects
				(font
					(size 0.7 0.7)
					(thickness 0.15)
				)
				(justify left bottom mirror)
			)
		)
		(fp_text user "Author: Antmicro"
			(at -0.72 -5.4 180)
			(layer "B.Fab")
			(effects
				(font
					(size 0.7 0.7)
					(thickness 0.15)
				)
				(justify left bottom mirror)
			)
		)
		(fp_text user "${REFERENCE}"
			(at -0.72 -3.4 180)
			(layer "B.Fab")
			(effects
				(font
					(size 0.7 0.7)
					(thickness 0.15)
				)
				(justify left bottom mirror)
			)
		)
		(pad "" smd roundrect
			(at -0.349 0.002)
			(size 0.318 0.36)
			(layers "B.Paste")
			(roundrect_rratio 0.25)
		)
		(pad "" smd roundrect
			(at 0.341 0.002)
			(size 0.318 0.36)
			(layers "B.Paste")
			(roundrect_rratio 0.25)
		)
		(pad "1" smd roundrect
			(at -0.321 0.002)
			(size 0.46 0.4)
			(layers "B.Cu" "B.Mask")
			(roundrect_rratio 0.25)
			(net 1 "GND")
			(pintype "passive")
		)
		(pad "2" smd roundrect
			(at 0.32 0.002)
			(size 0.46 0.4)
			(layers "B.Cu" "B.Mask")
			(roundrect_rratio 0.25)
			(net 9 "/FPGA Power/VCC_AUX")
			(pintype "passive")
		)
	)
	(footprint "antmicro-footprints:C_0201"
		(layer "B.Cu")
		(at 129.1 87.9 180)
		(descr "Capacitor SMD 0201")
		(tags "capacitor SMD 0201")
		(property "Reference" "C105"
			(at 7.87 12.095736 0)
			(layer "B.SilkS")
			(effects
				(font
					(size 0.65 0.65)
					(thickness 0.15)
				)
				(justify left bottom mirror)
			)
		)
		(property "Value" "C_100n_0201"
			(at 0 -1.4 0)
			(layer "B.Fab")
			(hide yes)
			(effects
				(font
					(size 0.7 0.7)
					(thickness 0.15)
				)
				(justify left bottom mirror)
			)
		)
		(property "Datasheet" "https://www.yageo.com/en/Chart/Download/pdf/CC0201KRX6S5BB104"
			(at 0 0 180)
			(layer "F.Fab")
			(hide yes)
			(effects
				(font
					(size 1.27 1.27)
					(thickness 0.15)
				)
			)
		)
		(property "Description" "SMD Multilayer Ceramic Capacitor, 0.1 µF, 6.3 V, 0201 [0603 Metric], ± 10%, X6S, CC Series"
			(at 0 0 180)
			(layer "F.Fab")
			(hide yes)
			(effects
				(font
					(size 1.27 1.27)
					(thickness 0.15)
				)
			)
		)
		(property "Author" "Antmicro"
			(at 258.2 175.8 0)
			(layer "B.Fab")
			(hide yes)
			(effects
				(font
					(size 1 1)
					(thickness 0.15)
				)
				(justify mirror)
			)
		)
		(property "Dielectric" ""
			(at 258.2 175.8 0)
			(layer "B.Fab")
			(hide yes)
			(effects
				(font
					(size 1 1)
					(thickness 0.15)
				)
				(justify mirror)
			)
		)
		(property "License" "Apache-2.0"
			(at 258.2 175.8 0)
			(layer "B.Fab")
			(hide yes)
			(effects
				(font
					(size 1 1)
					(thickness 0.15)
				)
				(justify mirror)
			)
		)
		(property "MPN" "CC0201KRX6S5BB104"
			(at 258.2 175.8 0)
			(layer "B.Fab")
			(hide yes)
			(effects
				(font
					(size 1 1)
					(thickness 0.15)
				)
				(justify mirror)
			)
		)
		(property "Manufacturer" "YAGEO"
			(at 258.2 175.8 0)
			(layer "B.Fab")
			(hide yes)
			(effects
				(font
					(size 1 1)
					(thickness 0.15)
				)
				(justify mirror)
			)
		)
		(property "Val" "100n"
			(at 258.2 175.8 0)
			(layer "B.Fab")
			(hide yes)
			(effects
				(font
					(size 1 1)
					(thickness 0.15)
				)
				(justify mirror)
			)
		)
		(property "Voltage" ""
			(at 258.2 175.8 0)
			(layer "B.Fab")
			(hide yes)
			(effects
				(font
					(size 1 1)
					(thickness 0.15)
				)
				(justify mirror)
			)
		)
		(property "Public" "False"
			(at 0 0 180)
			(unlocked yes)
			(layer "B.Fab")
			(hide yes)
			(effects
				(font
					(size 1 1)
					(thickness 0.15)
				)
				(justify mirror)
			)
		)
		(sheetname "/FPGA Power/")
		(sheetfile "FPGA_Power.kicad_sch")
		(attr smd)
		(fp_rect
			(start -0.7 0.35)
			(end 0.7 -0.35)
			(stroke
				(width 0.05)
				(type default)
			)
			(fill no)
			(layer "B.CrtYd")
		)
		(fp_rect
			(start 0.3 -0.15)
			(end -0.301 0.149)
			(stroke
				(width 0.15)
				(type solid)
			)
			(fill no)
			(layer "B.Fab")
		)
		(fp_text user "Author: Antmicro"
			(at -0.72 -5.4 0)
			(layer "B.Fab")
			(effects
				(font
					(size 0.7 0.7)
					(thickness 0.15)
				)
				(justify left bottom mirror)
			)
		)
		(fp_text user "${REFERENCE}"
			(at -0.72 -3.4 0)
			(layer "B.Fab")
			(effects
				(font
					(size 0.7 0.7)
					(thickness 0.15)
				)
				(justify left bottom mirror)
			)
		)
		(fp_text user "License: Apache-2.0"
			(at -0.72 -4.4 0)
			(layer "B.Fab")
			(effects
				(font
					(size 0.7 0.7)
					(thickness 0.15)
				)
				(justify left bottom mirror)
			)
		)
		(pad "" smd roundrect
			(at -0.349 0.002 180)
			(size 0.318 0.36)
			(layers "B.Paste")
			(roundrect_rratio 0.25)
		)
		(pad "" smd roundrect
			(at 0.341 0.002 180)
			(size 0.318 0.36)
			(layers "B.Paste")
			(roundrect_rratio 0.25)
		)
		(pad "1" smd roundrect
			(at -0.321 0.002 180)
			(size 0.46 0.4)
			(layers "B.Cu" "B.Mask")
			(roundrect_rratio 0.25)
			(net 1 "GND")
			(pintype "passive")
		)
		(pad "2" smd roundrect
			(at 0.32 0.002 180)
			(size 0.46 0.4)
			(layers "B.Cu" "B.Mask")
			(roundrect_rratio 0.25)
			(net 9 "/FPGA Power/VCC_AUX")
			(pintype "passive")
		)
	)
	(footprint "antmicro-footprints:R_0402_1005Metric"
		(layer "B.Cu")
		(at 103.19 96.8 -90)
		(descr "Resistor SMD 0402")
		(tags "resistor SMD 0402")
		(property "Reference" "R69"
			(at 0.94 -0.34 90)
			(layer "B.SilkS")
			(effects
				(font
					(size 0.65 0.65)
					(thickness 0.15)
				)
				(justify left bottom mirror)
			)
		)
		(property "Value" "R_0R_0402"
			(at 0 -1.4 90)
			(layer "B.Fab")
			(hide yes)
			(effects
				(font
					(size 0.7 0.7)
					(thickness 0.15)
				)
				(justify left bottom mirror)
			)
		)
		(property "Datasheet" "https://industrial.panasonic.com/cdbs/www-data/pdf/RDA0000/AOA0000C301.pdf"
			(at 0 0 270)
			(layer "F.Fab")
			(hide yes)
			(effects
				(font
					(size 1.27 1.27)
					(thickness 0.15)
				)
			)
		)
		(property "Description" "SMD Chip Resistor, Jumper, 0 ohm, 100 mW, 0402 [1005 Metric], Thick Film, General Purpose"
			(at 0 0 270)
			(layer "F.Fab")
			(hide yes)
			(effects
				(font
					(size 1.27 1.27)
					(thickness 0.15)
				)
			)
		)
		(property "Author" "Antmicro"
			(at 6.39 199.99 0)
			(layer "B.Fab")
			(hide yes)
			(effects
				(font
					(size 1 1)
					(thickness 0.15)
				)
				(justify mirror)
			)
		)
		(property "Current" "1A"
			(at 6.39 199.99 0)
			(layer "B.Fab")
			(hide yes)
			(effects
				(font
					(size 1 1)
					(thickness 0.15)
				)
				(justify mirror)
			)
		)
		(property "License" "Apache-2.0"
			(at 6.39 199.99 0)
			(layer "B.Fab")
			(hide yes)
			(effects
				(font
					(size 1 1)
					(thickness 0.15)
				)
				(justify mirror)
			)
		)
		(property "MPN" "ERJ2GE0R00X"
			(at 6.39 199.99 0)
			(layer "B.Fab")
			(hide yes)
			(effects
				(font
					(size 1 1)
					(thickness 0.15)
				)
				(justify mirror)
			)
		)
		(property "Manufacturer" "Panasonic"
			(at 6.39 199.99 0)
			(layer "B.Fab")
			(hide yes)
			(effects
				(font
					(size 1 1)
					(thickness 0.15)
				)
				(justify mirror)
			)
		)
		(property "Tolerance" "~"
			(at 6.39 199.99 0)
			(layer "B.Fab")
			(hide yes)
			(effects
				(font
					(size 1 1)
					(thickness 0.15)
				)
				(justify mirror)
			)
		)
		(property "Val" "0R"
			(at 6.39 199.99 0)
			(layer "B.Fab")
			(hide yes)
			(effects
				(font
					(size 1 1)
					(thickness 0.15)
				)
				(justify mirror)
			)
		)
		(sheetname "/FPGA/")
		(sheetfile "fpga.kicad_sch")
		(attr smd)
		(fp_rect
			(start -0.925 0.47)
			(end 0.925 -0.47)
			(stroke
				(width 0.05)
				(type default)
			)
			(fill no)
			(layer "B.CrtYd")
		)
		(fp_rect
			(start -0.5 0.25)
			(end 0.5 -0.25)
			(stroke
				(width 0.15)
				(type solid)
			)
			(fill no)
			(layer "B.Fab")
		)
		(fp_text user "${REFERENCE}"
			(at -0.95 -3.168 90)
			(layer "B.Fab")
			(effects
				(font
					(size 0.7 0.7)
					(thickness 0.15)
				)
				(justify left bottom mirror)
			)
		)
		(fp_text user "Author: Antmicro"
			(at -0.95 -4.169 90)
			(layer "B.Fab")
			(effects
				(font
					(size 0.7 0.7)
					(thickness 0.15)
				)
				(justify left bottom mirror)
			)
		)
		(fp_text user "License: Apache-2.0"
			(at -0.95 -5.169 90)
			(layer "B.Fab")
			(effects
				(font
					(size 0.7 0.7)
					(thickness 0.15)
				)
				(justify left bottom mirror)
			)
		)
		(pad "1" smd roundrect
			(at -0.48 0 270)
			(size 0.59 0.64)
			(layers "B.Cu" "B.Mask" "B.Paste")
			(roundrect_rratio 0.25)
			(net 300 "Net-(U18-SI{slash}IO0)")
			(pintype "passive")
		)
		(pad "2" smd roundrect
			(at 0.48 0 270)
			(size 0.59 0.64)
			(layers "B.Cu" "B.Mask" "B.Paste")
			(roundrect_rratio 0.25)
			(net 37 "/FPGA/SPI_DQ0_MOSI")
			(pintype "passive")
		)
	)
)
